(kicad_pcb
	(version 20260206)
	(generator "pcbnew")
	(generator_version "10.0")
	(general
		(thickness 1.6)
		(legacy_teardrops no)
	)
	(paper "A4")
	(title_block
		(title "v1-pdb — T6M_PDB_D_0927_0900.brd")
		(comment 1 "Open CloudServer (Microsoft) / footprints 245-246 of 321")
	)
	(layers
		(0 "F.Cu" signal "TOP")
		(4 "In1.Cu" signal "GND")
		(6 "In2.Cu" signal "IN1")
		(8 "In3.Cu" signal "VCC")
		(10 "In4.Cu" signal "VCC1")
		(12 "In5.Cu" signal "IN2")
		(14 "In6.Cu" signal "GND1")
		(2 "B.Cu" signal "BOTTOM")
		(9 "F.Adhes" user "F.Adhesive")
		(11 "B.Adhes" user "B.Adhesive")
		(13 "F.Paste" user "Package Geometry/Pastemask Top")
		(15 "B.Paste" user "Package Geometry/Pastemask Bottom")
		(5 "F.SilkS" user "Ref Des/Silkscreen Top")
		(7 "B.SilkS" user "Ref Des/Silkscreen Bottom")
		(1 "F.Mask" user "Board Geometry/Soldermask Top")
		(3 "B.Mask" user "Board Geometry/Soldermask Bottom")
		(17 "Dwgs.User" user "User.Drawings")
		(19 "Cmts.User" user "User.Comments")
		(21 "Eco1.User" user "User.Eco1")
		(23 "Eco2.User" user "User.Eco2")
		(25 "Edge.Cuts" user "Board Geometry/Outline")
		(27 "Margin" user)
		(31 "F.CrtYd" user "Package Geometry/Place Bound Top")
		(29 "B.CrtYd" user "Package Geometry/Place Bound Bottom")
		(35 "F.Fab" user "Ref Des/Assembly Top")
		(33 "B.Fab" user "Ref Des/Assembly Bottom")
	)
	(footprint ""
		(layer "F.Cu")
		(at 30.45968 -525.329912)
		(property "Reference" "J6"
			(at 8.641842 9.092438 90)
			(unlocked yes)
			(layer "F.SilkS")
			(effects
				(font
					(size 0.7874 0.5842)
					(thickness 0.1524)
				)
				(justify left)
			)
		)
		(property "Value" ""
			(at 0 0 0)
			(layer "F.Fab")
			(effects
				(font
					(size 1.27 1.27)
				)
			)
		)
		(duplicate_pad_numbers_are_jumpers no)
		(fp_line
			(start -2.135124 -4.560062)
			(end -2.135124 83.300062)
			(stroke
				(width 0.1524)
				(type default)
			)
			(layer "F.SilkS")
		)
		(fp_line
			(start -2.135124 83.300062)
			(end 7.215124 83.300062)
			(stroke
				(width 0.1524)
				(type default)
			)
			(layer "F.SilkS")
		)
		(fp_line
			(start 7.215124 -4.560062)
			(end -2.135124 -4.560062)
			(stroke
				(width 0.1524)
				(type default)
			)
			(layer "F.SilkS")
		)
		(fp_line
			(start 7.215124 83.300062)
			(end 7.215124 -4.560062)
			(stroke
				(width 0.1524)
				(type default)
			)
			(layer "F.SilkS")
		)
		(fp_poly
			(pts
				(xy -2.491486 0.079248) (xy -5.191506 -0.620776) (xy -5.191506 0.779272)
			)
			(stroke
				(width 0)
				(type default)
			)
			(fill yes)
			(layer "F.SilkS")
		)
		(fp_poly
			(pts
				(xy -2.28219 -0.127) (xy -4.98221 -0.827024) (xy -4.98221 0.573024)
			)
			(stroke
				(width 0)
				(type default)
			)
			(fill yes)
			(layer "B.SilkS")
		)
		(fp_poly
			(pts
				(xy -0.8636 -0.8636) (xy -0.8636 79.6036) (xy -0.8636 79.629) (xy 5.9436 79.629) (xy 5.9436 79.6036)
				(xy 5.9436 -0.8636) (xy 5.9436 -0.889) (xy -0.8636 -0.889)
			)
			(stroke
				(width 0)
				(type default)
			)
			(fill no)
			(layer "B.CrtYd")
		)
		(fp_rect
			(start -2.135124 -4.560062)
			(end 7.21487 83.300062)
			(stroke
				(width 0)
				(type default)
			)
			(fill no)
			(layer "F.CrtYd")
		)
		(fp_line
			(start -2.135124 -4.560062)
			(end 7.215124 -4.560062)
			(stroke
				(width 0.1)
				(type default)
			)
			(layer "F.Fab")
		)
		(fp_line
			(start -2.135124 83.300062)
			(end -2.135124 -4.560062)
			(stroke
				(width 0.1)
				(type default)
			)
			(layer "F.Fab")
		)
		(fp_line
			(start 7.215124 -4.560062)
			(end 7.215124 83.300062)
			(stroke
				(width 0.1)
				(type default)
			)
			(layer "F.Fab")
		)
		(fp_line
			(start 7.215124 83.300062)
			(end -2.135124 83.300062)
			(stroke
				(width 0.1)
				(type default)
			)
			(layer "F.Fab")
		)
		(fp_text user "32"
			(at -4.215638 79.904082 0)
			(unlocked yes)
			(layer "F.SilkS")
			(effects
				(font
					(size 0.7874 0.5842)
					(thickness 0.1524)
				)
				(justify left)
			)
		)
		(fp_text user "1"
			(at -3.120644 -1.027176 0)
			(unlocked yes)
			(layer "F.SilkS")
			(effects
				(font
					(size 0.7874 0.5842)
					(thickness 0.1524)
				)
				(justify left)
			)
		)
		(fp_text user "64"
			(at 7.523988 -0.308864 0)
			(unlocked yes)
			(layer "F.SilkS")
			(effects
				(font
					(size 0.7874 0.5842)
					(thickness 0.1524)
				)
				(justify left)
			)
		)
		(fp_text user "33"
			(at 7.80161 81.392268 0)
			(unlocked yes)
			(layer "F.SilkS")
			(effects
				(font
					(size 0.7874 0.5842)
					(thickness 0.1524)
				)
				(justify left)
			)
		)
		(fp_text user "32"
			(at -1.360678 79.256636 0)
			(unlocked yes)
			(layer "B.SilkS")
			(effects
				(font
					(size 0.7874 0.5842)
					(thickness 0.1524)
				)
				(justify left mirror)
			)
		)
		(fp_text user "1"
			(at -1.297686 -1.511046 0)
			(unlocked yes)
			(layer "B.SilkS")
			(effects
				(font
					(size 0.7874 0.5842)
					(thickness 0.1524)
				)
				(justify left mirror)
			)
		)
		(fp_text user "33"
			(at 5.67055 81.353152 0)
			(unlocked yes)
			(layer "B.SilkS")
			(effects
				(font
					(size 0.7874 0.5842)
					(thickness 0.1524)
				)
				(justify left mirror)
			)
		)
		(fp_text user "64"
			(at 5.908802 -1.856994 0)
			(unlocked yes)
			(layer "B.SilkS")
			(effects
				(font
					(size 0.7874 0.5842)
					(thickness 0.1524)
				)
				(justify left mirror)
			)
		)
		(pad "1" thru_hole rect
			(at 0 0 270)
			(size 1.6256 1.6256)
			(drill 1.1176)
			(layers "*.Cu" "*.Mask")
			(remove_unused_layers no)
			(net "P12V")
			(clearance 0)
			(padstack
				(mode front_inner_back)
				(layer "Inner"
					(shape circle)
					(size 1.6256 1.6256)
					(clearance 0)
				)
				(layer "B.Cu"
					(shape rect)
					(size 1.6256 1.6256)
					(clearance 0)
				)
			)
		)
		(pad "2" thru_hole circle
			(at 0 2.54 270)
			(size 1.6256 1.6256)
			(drill 1.1176)
			(layers "*.Cu" "*.Mask")
			(remove_unused_layers no)
			(net "P12V")
			(clearance 0)
		)
		(pad "3" thru_hole circle
			(at 0 5.08 270)
			(size 1.6256 1.6256)
			(drill 1.1176)
			(layers "*.Cu" "*.Mask")
			(remove_unused_layers no)
			(net "P12V")
			(clearance 0)
		)
		(pad "4" thru_hole circle
			(at 0 7.62 270)
			(size 1.6256 1.6256)
			(drill 1.1176)
			(layers "*.Cu" "*.Mask")
			(remove_unused_layers no)
			(net "P12V")
			(clearance 0)
		)
		(pad "5" thru_hole circle
			(at 0 10.16 270)
			(size 1.6256 1.6256)
			(drill 1.1176)
			(layers "*.Cu" "*.Mask")
			(remove_unused_layers no)
			(net "P12V")
			(clearance 0)
		)
		(pad "6" thru_hole circle
			(at 0 12.7 270)
			(size 1.6256 1.6256)
			(drill 1.1176)
			(layers "*.Cu" "*.Mask")
			(remove_unused_layers no)
			(net "P12V")
			(clearance 0)
		)
		(pad "7" thru_hole circle
			(at 0 15.24 270)
			(size 1.6256 1.6256)
			(drill 1.1176)
			(layers "*.Cu" "*.Mask")
			(remove_unused_layers no)
			(net "P12V")
			(clearance 0)
		)
		(pad "8" thru_hole circle
			(at 0 17.78 270)
			(size 1.6256 1.6256)
			(drill 1.1176)
			(layers "*.Cu" "*.Mask")
			(remove_unused_layers no)
			(net "P12V")
			(clearance 0)
		)
		(pad "9" thru_hole circle
			(at 0 20.32 270)
			(size 1.6256 1.6256)
			(drill 1.1176)
			(layers "*.Cu" "*.Mask")
			(remove_unused_layers no)
			(net "P12V")
			(clearance 0)
		)
		(pad "10" thru_hole circle
			(at 0 22.86 270)
			(size 1.6256 1.6256)
			(drill 1.1176)
			(layers "*.Cu" "*.Mask")
			(remove_unused_layers no)
			(net "P12V")
			(clearance 0)
		)
		(pad "11" thru_hole circle
			(at 0 25.4 270)
			(size 1.6256 1.6256)
			(drill 1.1176)
			(layers "*.Cu" "*.Mask")
			(remove_unused_layers no)
			(net "P12V")
			(clearance 0)
		)
		(pad "12" thru_hole circle
			(at 0 27.94 270)
			(size 1.6256 1.6256)
			(drill 1.1176)
			(layers "*.Cu" "*.Mask")
			(remove_unused_layers no)
			(net "P12V")
			(clearance 0)
		)
		(pad "13" thru_hole circle
			(at 0 30.48 270)
			(size 1.6256 1.6256)
			(drill 1.1176)
			(layers "*.Cu" "*.Mask")
			(remove_unused_layers no)
			(net "GND")
			(clearance 0)
		)
		(pad "14" thru_hole circle
			(at 0 33.02 270)
			(size 1.6256 1.6256)
			(drill 1.1176)
			(layers "*.Cu" "*.Mask")
			(remove_unused_layers no)
			(net "GND")
			(clearance 0)
		)
		(pad "15" thru_hole circle
			(at 0 35.56 270)
			(size 1.6256 1.6256)
			(drill 1.1176)
			(layers "*.Cu" "*.Mask")
			(remove_unused_layers no)
			(net "GND")
			(clearance 0)
		)
		(pad "16" thru_hole circle
			(at 0 38.1 270)
			(size 1.6256 1.6256)
			(drill 1.1176)
			(layers "*.Cu" "*.Mask")
			(remove_unused_layers no)
			(net "GND")
			(clearance 0)
		)
		(pad "17" thru_hole circle
			(at 0 40.64 270)
			(size 1.6256 1.6256)
			(drill 1.1176)
			(layers "*.Cu" "*.Mask")
			(remove_unused_layers no)
			(net "GND")
			(clearance 0)
		)
		(pad "18" thru_hole circle
			(at 0 43.18 270)
			(size 1.6256 1.6256)
			(drill 1.1176)
			(layers "*.Cu" "*.Mask")
			(remove_unused_layers no)
			(net "GND")
			(clearance 0)
		)
		(pad "19" thru_hole circle
			(at 0 45.72 270)
			(size 1.6256 1.6256)
			(drill 1.1176)
			(layers "*.Cu" "*.Mask")
			(remove_unused_layers no)
			(net "GND")
			(clearance 0)
		)
		(pad "20" thru_hole circle
			(at 0 48.26 270)
			(size 1.6256 1.6256)
			(drill 1.1176)
			(layers "*.Cu" "*.Mask")
			(remove_unused_layers no)
			(net "GND")
			(clearance 0)
		)
		(pad "21" thru_hole circle
			(at 0 50.8 270)
			(size 1.6256 1.6256)
			(drill 1.1176)
			(layers "*.Cu" "*.Mask")
			(remove_unused_layers no)
			(net "GND")
			(clearance 0)
		)
		(pad "22" thru_hole circle
			(at 0 53.34 270)
			(size 1.6256 1.6256)
			(drill 1.1176)
			(layers "*.Cu" "*.Mask")
			(remove_unused_layers no)
			(net "GND")
			(clearance 0)
		)
		(pad "23" thru_hole circle
			(at 0 55.88 270)
			(size 1.6256 1.6256)
			(drill 1.1176)
			(layers "*.Cu" "*.Mask")
			(remove_unused_layers no)
			(net "GND")
			(clearance 0)
		)
		(pad "24" thru_hole circle
			(at 0 58.42 270)
			(size 1.6256 1.6256)
			(drill 1.1176)
			(layers "*.Cu" "*.Mask")
			(remove_unused_layers no)
			(net "GND")
			(clearance 0)
		)
		(pad "25" thru_hole circle
			(at 0 60.96 270)
			(size 1.6256 1.6256)
			(drill 1.1176)
			(layers "*.Cu" "*.Mask")
			(remove_unused_layers no)
			(net "Net_397")
			(clearance 0)
		)
		(pad "26" thru_hole circle
			(at 0 63.5 270)
			(size 1.6256 1.6256)
			(drill 1.1176)
			(layers "*.Cu" "*.Mask")
			(remove_unused_layers no)
			(net "PSU6_REMOTE_N")
			(clearance 0)
		)
		(pad "27" thru_hole circle
			(at 0 66.04 270)
			(size 1.6256 1.6256)
			(drill 1.1176)
			(layers "*.Cu" "*.Mask")
			(remove_unused_layers no)
			(net "PSU6_AC_OK")
			(clearance 0)
		)
		(pad "28" thru_hole circle
			(at 0 68.58 270)
			(size 1.6256 1.6256)
			(drill 1.1176)
			(layers "*.Cu" "*.Mask")
			(remove_unused_layers no)
			(net "PSU6_CSAHRE")
			(clearance 0)
		)
		(pad "29" thru_hole circle
			(at 0 71.12 270)
			(size 1.6256 1.6256)
			(drill 1.1176)
			(layers "*.Cu" "*.Mask")
			(remove_unused_layers no)
			(net "PSU6_PS_ON_N")
			(clearance 0)
		)
		(pad "30" thru_hole circle
			(at 0 73.66 270)
			(size 1.6256 1.6256)
			(drill 1.1176)
			(layers "*.Cu" "*.Mask")
			(remove_unused_layers no)
			(net "PSU6_PS_KILL")
			(clearance 0)
		)
		(pad "31" thru_hole circle
			(at 0 76.2 270)
			(size 1.6256 1.6256)
			(drill 1.1176)
			(layers "*.Cu" "*.Mask")
			(remove_unused_layers no)
			(net "PSU6_RESET")
			(clearance 0)
		)
		(pad "32" thru_hole circle
			(at 0 78.74 270)
			(size 1.6256 1.6256)
			(drill 1.1176)
			(layers "*.Cu" "*.Mask")
			(remove_unused_layers no)
			(net "PSU_ALERT_N")
			(clearance 0)
		)
		(pad "33" thru_hole circle
			(at 5.08 78.74 270)
			(size 1.6256 1.6256)
			(drill 1.1176)
			(layers "*.Cu" "*.Mask")
			(remove_unused_layers no)
			(net "I2C_PSU3_SDA")
			(clearance 0)
		)
		(pad "34" thru_hole circle
			(at 5.08 76.2 270)
			(size 1.6256 1.6256)
			(drill 1.1176)
			(layers "*.Cu" "*.Mask")
			(remove_unused_layers no)
			(net "Net_398")
			(clearance 0)
		)
		(pad "35" thru_hole circle
			(at 5.08 73.66 270)
			(size 1.6256 1.6256)
			(drill 1.1176)
			(layers "*.Cu" "*.Mask")
			(remove_unused_layers no)
			(net "I2C_PSU3_SCL")
			(clearance 0)
		)
		(pad "36" thru_hole circle
			(at 5.08 71.12 270)
			(size 1.6256 1.6256)
			(drill 1.1176)
			(layers "*.Cu" "*.Mask")
			(remove_unused_layers no)
			(net "PSU6_RETURN")
			(clearance 0)
		)
		(pad "37" thru_hole circle
			(at 5.08 68.58 270)
			(size 1.6256 1.6256)
			(drill 1.1176)
			(layers "*.Cu" "*.Mask")
			(remove_unused_layers no)
			(net "PSU6_DC_OK")
			(clearance 0)
		)
		(pad "38" thru_hole circle
			(at 5.08 66.04 270)
			(size 1.6256 1.6256)
			(drill 1.1176)
			(layers "*.Cu" "*.Mask")
			(remove_unused_layers no)
			(net "PSU6_AD0")
			(clearance 0)
		)
		(pad "39" thru_hole circle
			(at 5.08 63.5 270)
			(size 1.6256 1.6256)
			(drill 1.1176)
			(layers "*.Cu" "*.Mask")
			(remove_unused_layers no)
			(net "P12V_STBY")
			(clearance 0)
		)
		(pad "40" thru_hole circle
			(at 5.08 60.96 270)
			(size 1.6256 1.6256)
			(drill 1.1176)
			(layers "*.Cu" "*.Mask")
			(remove_unused_layers no)
			(net "PSU6_REMOTE_P")
			(clearance 0)
		)
		(pad "41" thru_hole circle
			(at 5.08 58.42 270)
			(size 1.6256 1.6256)
			(drill 1.1176)
			(layers "*.Cu" "*.Mask")
			(remove_unused_layers no)
			(net "GND")
			(clearance 0)
		)
		(pad "42" thru_hole circle
			(at 5.08 55.88 270)
			(size 1.6256 1.6256)
			(drill 1.1176)
			(layers "*.Cu" "*.Mask")
			(remove_unused_layers no)
			(net "GND")
			(clearance 0)
		)
		(pad "43" thru_hole circle
			(at 5.08 53.34 270)
			(size 1.6256 1.6256)
			(drill 1.1176)
			(layers "*.Cu" "*.Mask")
			(remove_unused_layers no)
			(net "GND")
			(clearance 0)
		)
		(pad "44" thru_hole circle
			(at 5.08 50.8 270)
			(size 1.6256 1.6256)
			(drill 1.1176)
			(layers "*.Cu" "*.Mask")
			(remove_unused_layers no)
			(net "GND")
			(clearance 0)
		)
		(pad "45" thru_hole circle
			(at 5.08 48.26 270)
			(size 1.6256 1.6256)
			(drill 1.1176)
			(layers "*.Cu" "*.Mask")
			(remove_unused_layers no)
			(net "GND")
			(clearance 0)
		)
		(pad "46" thru_hole circle
			(at 5.08 45.72 270)
			(size 1.6256 1.6256)
			(drill 1.1176)
			(layers "*.Cu" "*.Mask")
			(remove_unused_layers no)
			(net "GND")
			(clearance 0)
		)
		(pad "47" thru_hole circle
			(at 5.08 43.18 270)
			(size 1.6256 1.6256)
			(drill 1.1176)
			(layers "*.Cu" "*.Mask")
			(remove_unused_layers no)
			(net "GND")
			(clearance 0)
		)
		(pad "48" thru_hole circle
			(at 5.08 40.64 270)
			(size 1.6256 1.6256)
			(drill 1.1176)
			(layers "*.Cu" "*.Mask")
			(remove_unused_layers no)
			(net "GND")
			(clearance 0)
		)
		(pad "49" thru_hole circle
			(at 5.08 38.1 270)
			(size 1.6256 1.6256)
			(drill 1.1176)
			(layers "*.Cu" "*.Mask")
			(remove_unused_layers no)
			(net "GND")
			(clearance 0)
		)
		(pad "50" thru_hole circle
			(at 5.08 35.56 270)
			(size 1.6256 1.6256)
			(drill 1.1176)
			(layers "*.Cu" "*.Mask")
			(remove_unused_layers no)
			(net "GND")
			(clearance 0)
		)
		(pad "51" thru_hole circle
			(at 5.08 33.02 270)
			(size 1.6256 1.6256)
			(drill 1.1176)
			(layers "*.Cu" "*.Mask")
			(remove_unused_layers no)
			(net "GND")
			(clearance 0)
		)
		(pad "52" thru_hole circle
			(at 5.08 30.48 270)
			(size 1.6256 1.6256)
			(drill 1.1176)
			(layers "*.Cu" "*.Mask")
			(remove_unused_layers no)
			(net "GND")
			(clearance 0)
		)
		(pad "53" thru_hole circle
			(at 5.08 27.94 270)
			(size 1.6256 1.6256)
			(drill 1.1176)
			(layers "*.Cu" "*.Mask")
			(remove_unused_layers no)
			(net "P12V")
			(clearance 0)
		)
		(pad "54" thru_hole circle
			(at 5.08 25.4 270)
			(size 1.6256 1.6256)
			(drill 1.1176)
			(layers "*.Cu" "*.Mask")
			(remove_unused_layers no)
			(net "P12V")
			(clearance 0)
		)
		(pad "55" thru_hole circle
			(at 5.08 22.86 270)
			(size 1.6256 1.6256)
			(drill 1.1176)
			(layers "*.Cu" "*.Mask")
			(remove_unused_layers no)
			(net "P12V")
			(clearance 0)
		)
		(pad "56" thru_hole circle
			(at 5.08 20.32 270)
			(size 1.6256 1.6256)
			(drill 1.1176)
			(layers "*.Cu" "*.Mask")
			(remove_unused_layers no)
			(net "P12V")
			(clearance 0)
		)
		(pad "57" thru_hole circle
			(at 5.08 17.78 270)
			(size 1.6256 1.6256)
			(drill 1.1176)
			(layers "*.Cu" "*.Mask")
			(remove_unused_layers no)
			(net "P12V")
			(clearance 0)
		)
		(pad "58" thru_hole circle
			(at 5.08 15.24 270)
			(size 1.6256 1.6256)
			(drill 1.1176)
			(layers "*.Cu" "*.Mask")
			(remove_unused_layers no)
			(net "P12V")
			(clearance 0)
		)
		(pad "59" thru_hole circle
			(at 5.08 12.7 270)
			(size 1.6256 1.6256)
			(drill 1.1176)
			(layers "*.Cu" "*.Mask")
			(remove_unused_layers no)
			(net "P12V")
			(clearance 0)
		)
		(pad "60" thru_hole circle
			(at 5.08 10.16 270)
			(size 1.6256 1.6256)
			(drill 1.1176)
			(layers "*.Cu" "*.Mask")
			(remove_unused_layers no)
			(net "P12V")
			(clearance 0)
		)
		(pad "61" thru_hole circle
			(at 5.08 7.62 270)
			(size 1.6256 1.6256)
			(drill 1.1176)
			(layers "*.Cu" "*.Mask")
			(remove_unused_layers no)
			(net "P12V")
			(clearance 0)
		)
		(pad "62" thru_hole circle
			(at 5.08 5.08 270)
			(size 1.6256 1.6256)
			(drill 1.1176)
			(layers "*.Cu" "*.Mask")
			(remove_unused_layers no)
			(net "P12V")
			(clearance 0)
		)
		(pad "63" thru_hole circle
			(at 5.08 2.54 270)
			(size 1.6256 1.6256)
			(drill 1.1176)
			(layers "*.Cu" "*.Mask")
			(remove_unused_layers no)
			(net "P12V")
			(clearance 0)
		)
		(pad "64" thru_hole circle
			(at 5.08 0 270)
			(size 1.6256 1.6256)
			(drill 1.1176)
			(layers "*.Cu" "*.Mask")
			(remove_unused_layers no)
			(net "P12V")
			(clearance 0)
		)
	)
	(footprint ""
		(layer "F.Cu")
		(at 98.702114 -15.774924)
		(property "Reference" ""
			(at 0 0 0)
			(layer "F.SilkS")
			(hide yes)
			(effects
				(font
					(size 1.27 1.27)
				)
			)
		)
		(property "Value" ""
			(at 0 0 0)
			(layer "F.Fab")
			(effects
				(font
					(size 1.27 1.27)
				)
			)
		)
		(duplicate_pad_numbers_are_jumpers no)
		(fp_poly
			(pts
				(arc
					(start 1.4986 0)
					(mid -1.4986 0)
					(end 1.4986 0)
				)
			)
			(stroke
				(width 0)
				(type default)
			)
			(fill no)
			(layer "F.CrtYd")
		)
		(pad "1" smd circle
			(at 0 0)
			(size 0.9906 0.9906)
			(layers "F.Cu" "F.Mask" "F.Paste")
			(net "Net_172")
		)
		(zone
			(layer "F.Cu")
			(hatch none 0.5)
			(connect_pads
				(clearance 0)
			)
			(min_thickness 0.25)
			(keepout
				(tracks not_allowed)
				(vias allowed)
				(pads allowed)
				(copperpour not_allowed)
				(footprints allowed)
			)
			(placement
				(enabled no)
				(sheetname "")
			)
			(fill
				(thermal_gap 0.5)
				(thermal_bridge_width 0.5)
				(island_removal_mode 0)
			)
			(polygon
				(pts
					(arc
						(start 100.327714 -15.774924)
						(mid 97.076514 -15.774924)
						(end 100.327714 -15.774924)
					)
				)
			)
		)
	)
)
